(kicad_pcb
	(version 20260206)
	(generator "pcbnew")
	(generator_version "10.0")
	(general
		(thickness 1.6)
		(legacy_teardrops no)
	)
	(paper "A4")
	(title_block
		(title "panther-plus-userver — 13130-1b_20150205.brd")
		(comment 1 "Honey Badger (Wiwynn) / footprints 1203-1210 of 1509")
	)
	(layers
		(0 "F.Cu" signal "TOP")
		(4 "In1.Cu" signal "L2")
		(6 "In2.Cu" signal "L3")
		(8 "In3.Cu" signal "L4")
		(10 "In4.Cu" signal "L5")
		(12 "In5.Cu" signal "L6")
		(14 "In6.Cu" signal "L7")
		(16 "In7.Cu" signal "L8")
		(18 "In8.Cu" signal "L9")
		(20 "In9.Cu" signal "L10")
		(22 "In10.Cu" signal "L11")
		(2 "B.Cu" signal "BOTTOM")
		(9 "F.Adhes" user "F.Adhesive")
		(11 "B.Adhes" user "B.Adhesive")
		(13 "F.Paste" user "Package Geometry/Pastemask Top")
		(15 "B.Paste" user "Package Geometry/Pastemask Bottom")
		(5 "F.SilkS" user "Ref Des/Silkscreen Top")
		(7 "B.SilkS" user "Ref Des/Silkscreen Bottom")
		(1 "F.Mask" user "Board Geometry/Soldermask Top")
		(3 "B.Mask" user "Board Geometry/Soldermask Bottom")
		(17 "Dwgs.User" user "User.Drawings")
		(19 "Cmts.User" user "User.Comments")
		(21 "Eco1.User" user "User.Eco1")
		(23 "Eco2.User" user "User.Eco2")
		(25 "Edge.Cuts" user "Board Geometry/Outline")
		(27 "Margin" user)
		(31 "F.CrtYd" user "Package Geometry/Place Bound Top")
		(29 "B.CrtYd" user "Package Geometry/Place Bound Bottom")
		(35 "F.Fab" user "Ref Des/Assembly Top")
		(33 "B.Fab" user "Ref Des/Assembly Bottom")
	)
	(footprint ""
		(layer "B.Cu")
		(at 156.4386 -12.828778 180)
		(property "Reference" "C364"
			(at 0 0 0)
			(layer "B.SilkS")
			(hide yes)
			(effects
				(font
					(size 1.27 1.27)
				)
				(justify mirror)
			)
		)
		(property "Value" "SC47U6D3V5MX-1-GP"
			(at 0 -4.9022 180)
			(unlocked yes)
			(layer "B.Fab")
			(hide yes)
			(effects
				(font
					(size 1.016 1.016)
					(thickness 0.1524)
				)
				(justify mirror)
			)
		)
		(property "Device Type" "C805H54"
			(at 0 -6.8072 180)
			(unlocked yes)
			(layer "B.Fab")
			(hide yes)
			(effects
				(font
					(size 1.016 1.016)
					(thickness 0.1524)
				)
				(justify mirror)
			)
		)
		(duplicate_pad_numbers_are_jumpers no)
		(fp_line
			(start -0.6096 0)
			(end 0.6096 0)
			(stroke
				(width 0.3048)
				(type default)
			)
			(layer "B.SilkS")
		)
		(fp_poly
			(pts
				(xy 0.9017 1.4351) (xy -0.9017 1.4351) (xy -0.9017 -1.4351) (xy 0.9017 -1.4351)
			)
			(stroke
				(width 0)
				(type default)
			)
			(fill no)
			(layer "B.CrtYd")
		)
		(fp_poly
			(pts
				(xy -0.9017 1.4351) (xy -0.9017 -1.4351) (xy 0.9017 -1.4351) (xy 0.9017 1.4351)
			)
			(stroke
				(width 0)
				(type default)
			)
			(fill no)
			(layer "B.Fab")
		)
		(pad "1" smd rect
			(at 0 -0.8382)
			(size 1.5494 0.9398)
			(layers "B.Cu" "B.Mask" "B.Paste")
			(net "PV_VDDR")
		)
		(pad "2" smd rect
			(at 0 0.8382)
			(size 1.5494 0.9398)
			(layers "B.Cu" "B.Mask" "B.Paste")
			(net "GND")
		)
	)
	(footprint ""
		(layer "B.Cu")
		(at 120.777 -68.7578)
		(property "Reference" "R236"
			(at 0 0 0)
			(layer "B.SilkS")
			(hide yes)
			(effects
				(font
					(size 1.27 1.27)
				)
				(justify mirror)
			)
		)
		(property "Value" "0R2J-2-GP"
			(at -0.064008 -3.993896 0)
			(unlocked yes)
			(layer "B.Fab")
			(hide yes)
			(effects
				(font
					(size 1.016 1.016)
					(thickness 0.1524)
				)
				(justify mirror)
			)
		)
		(property "Device Type" "R402H16"
			(at -0.064008 -5.517896 0)
			(unlocked yes)
			(layer "B.Fab")
			(hide yes)
			(effects
				(font
					(size 1.016 1.016)
					(thickness 0.1524)
				)
				(justify mirror)
			)
		)
		(duplicate_pad_numbers_are_jumpers no)
		(fp_rect
			(start 0.381 0.8382)
			(end -0.381 -0.8382)
			(stroke
				(width 0)
				(type default)
			)
			(fill no)
			(layer "B.CrtYd")
		)
		(fp_rect
			(start 0.381 0.8382)
			(end -0.381 -0.8382)
			(stroke
				(width 0)
				(type default)
			)
			(fill no)
			(layer "B.Fab")
		)
		(pad "1" smd custom
			(at 0 -0.4318 180)
			(size 0.127 0.127)
			(layers "B.Cu" "B.Mask" "B.Paste")
			(net "SMB_M_A0_R_CLK")
			(options
				(clearance outline)
				(anchor circle)
			)
			(primitives
				(gr_poly
					(pts
						(arc
							(start -0.2032 0.2794)
							(mid -0.239121 0.264521)
							(end -0.254 0.2286)
						)
						(arc
							(start -0.254 -0.2286)
							(mid -0.239121 -0.264521)
							(end -0.2032 -0.2794)
						)
						(arc
							(start 0.2032 -0.2794)
							(mid 0.239121 -0.264521)
							(end 0.254 -0.2286)
						)
						(arc
							(start 0.254 0.2286)
							(mid 0.239121 0.264521)
							(end 0.2032 0.2794)
						)
					)
					(width 0)
					(fill yes)
				)
			)
		)
		(pad "2" smd custom
			(at 0 0.4318 180)
			(size 0.127 0.127)
			(layers "B.Cu" "B.Mask" "B.Paste")
			(net "SMB_HOST_LV_CLK")
			(options
				(clearance outline)
				(anchor circle)
			)
			(primitives
				(gr_poly
					(pts
						(arc
							(start -0.2032 0.2794)
							(mid -0.239121 0.264521)
							(end -0.254 0.2286)
						)
						(arc
							(start -0.254 -0.2286)
							(mid -0.239121 -0.264521)
							(end -0.2032 -0.2794)
						)
						(arc
							(start 0.2032 -0.2794)
							(mid 0.239121 -0.264521)
							(end 0.254 -0.2286)
						)
						(arc
							(start 0.254 0.2286)
							(mid 0.239121 0.264521)
							(end 0.2032 0.2794)
						)
					)
					(width 0)
					(fill yes)
				)
			)
		)
	)
	(footprint ""
		(layer "B.Cu")
		(at 92.329 -13.462)
		(property "Reference" "R340"
			(at 0 0 0)
			(layer "B.SilkS")
			(hide yes)
			(effects
				(font
					(size 1.27 1.27)
				)
				(justify mirror)
			)
		)
		(property "Value" "0R2J-2-GP"
			(at -0.064008 -3.993896 0)
			(unlocked yes)
			(layer "B.Fab")
			(hide yes)
			(effects
				(font
					(size 1.016 1.016)
					(thickness 0.1524)
				)
				(justify mirror)
			)
		)
		(property "Device Type" "R402H16"
			(at -0.064008 -5.517896 0)
			(unlocked yes)
			(layer "B.Fab")
			(hide yes)
			(effects
				(font
					(size 1.016 1.016)
					(thickness 0.1524)
				)
				(justify mirror)
			)
		)
		(duplicate_pad_numbers_are_jumpers no)
		(fp_rect
			(start 0.381 0.8382)
			(end -0.381 -0.8382)
			(stroke
				(width 0)
				(type default)
			)
			(fill no)
			(layer "B.CrtYd")
		)
		(fp_rect
			(start 0.381 0.8382)
			(end -0.381 -0.8382)
			(stroke
				(width 0)
				(type default)
			)
			(fill no)
			(layer "B.Fab")
		)
		(pad "1" smd custom
			(at 0 -0.4318 180)
			(size 0.127 0.127)
			(layers "B.Cu" "B.Mask" "B.Paste")
			(net "BMC_PWRBTN#")
			(options
				(clearance outline)
				(anchor circle)
			)
			(primitives
				(gr_poly
					(pts
						(arc
							(start -0.2032 0.2794)
							(mid -0.239121 0.264521)
							(end -0.254 0.2286)
						)
						(arc
							(start -0.254 -0.2286)
							(mid -0.239121 -0.264521)
							(end -0.2032 -0.2794)
						)
						(arc
							(start 0.2032 -0.2794)
							(mid 0.239121 -0.264521)
							(end 0.254 -0.2286)
						)
						(arc
							(start 0.254 0.2286)
							(mid 0.239121 0.264521)
							(end 0.2032 0.2794)
						)
					)
					(width 0)
					(fill yes)
				)
			)
		)
		(pad "2" smd custom
			(at 0 0.4318 180)
			(size 0.127 0.127)
			(layers "B.Cu" "B.Mask" "B.Paste")
			(net "PWR_BTN#")
			(options
				(clearance outline)
				(anchor circle)
			)
			(primitives
				(gr_poly
					(pts
						(arc
							(start -0.2032 0.2794)
							(mid -0.239121 0.264521)
							(end -0.254 0.2286)
						)
						(arc
							(start -0.254 -0.2286)
							(mid -0.239121 -0.264521)
							(end -0.2032 -0.2794)
						)
						(arc
							(start 0.2032 -0.2794)
							(mid 0.239121 -0.264521)
							(end 0.254 -0.2286)
						)
						(arc
							(start 0.254 0.2286)
							(mid 0.239121 0.264521)
							(end 0.2032 0.2794)
						)
					)
					(width 0)
					(fill yes)
				)
			)
		)
	)
	(footprint ""
		(layer "B.Cu")
		(at 112.395 -28.337002 90)
		(property "Reference" "C230"
			(at 0 0 90)
			(layer "B.SilkS")
			(hide yes)
			(effects
				(font
					(size 1.27 1.27)
				)
				(justify mirror)
			)
		)
		(property "Value" "SCD1U16V2KX-3GP"
			(at -1.1811 -2.7051 90)
			(unlocked yes)
			(layer "B.Fab")
			(hide yes)
			(effects
				(font
					(size 1.016 1.016)
					(thickness 0.1524)
				)
				(justify mirror)
			)
		)
		(property "Device Type" "C402H22"
			(at -1.1811 -4.2291 90)
			(unlocked yes)
			(layer "B.Fab")
			(hide yes)
			(effects
				(font
					(size 1.016 1.016)
					(thickness 0.1524)
				)
				(justify mirror)
			)
		)
		(duplicate_pad_numbers_are_jumpers no)
		(fp_rect
			(start 0.381 0.7366)
			(end -0.381 -0.7366)
			(stroke
				(width 0)
				(type default)
			)
			(fill no)
			(layer "B.CrtYd")
		)
		(fp_rect
			(start 0.381 0.7366)
			(end -0.381 -0.7366)
			(stroke
				(width 0)
				(type default)
			)
			(fill no)
			(layer "B.Fab")
		)
		(pad "1" smd custom
			(at 0 -0.4572 270)
			(size 0.1143 0.1143)
			(layers "B.Cu" "B.Mask" "B.Paste")
			(net "PV_VDDR")
			(options
				(clearance outline)
				(anchor circle)
			)
			(primitives
				(gr_poly
					(pts
						(arc
							(start -0.254 0.1778)
							(mid -0.239121 0.213721)
							(end -0.2032 0.2286)
						)
						(arc
							(start 0.2032 0.2286)
							(mid 0.239121 0.213721)
							(end 0.254 0.1778)
						)
						(arc
							(start 0.254 -0.1778)
							(mid 0.239121 -0.213721)
							(end 0.2032 -0.2286)
						)
						(arc
							(start -0.2032 -0.2286)
							(mid -0.239121 -0.213721)
							(end -0.254 -0.1778)
						)
					)
					(width 0)
					(fill yes)
				)
			)
		)
		(pad "2" smd custom
			(at 0 0.4572 270)
			(size 0.1143 0.1143)
			(layers "B.Cu" "B.Mask" "B.Paste")
			(net "GND")
			(options
				(clearance outline)
				(anchor circle)
			)
			(primitives
				(gr_poly
					(pts
						(arc
							(start -0.254 0.1778)
							(mid -0.239121 0.213721)
							(end -0.2032 0.2286)
						)
						(arc
							(start 0.2032 0.2286)
							(mid 0.239121 0.213721)
							(end 0.254 0.1778)
						)
						(arc
							(start 0.254 -0.1778)
							(mid 0.239121 -0.213721)
							(end 0.2032 -0.2286)
						)
						(arc
							(start -0.2032 -0.2286)
							(mid -0.239121 -0.213721)
							(end -0.254 -0.1778)
						)
					)
					(width 0)
					(fill yes)
				)
			)
		)
	)
	(footprint ""
		(layer "B.Cu")
		(at 37.719 -22.733 -90)
		(property "Reference" "R354"
			(at 0 0 90)
			(layer "B.SilkS")
			(hide yes)
			(effects
				(font
					(size 1.27 1.27)
				)
				(justify mirror)
			)
		)
		(property "Value" "33R2F-3-GP"
			(at -0.064008 -3.993896 270)
			(unlocked yes)
			(layer "B.Fab")
			(hide yes)
			(effects
				(font
					(size 1.016 1.016)
					(thickness 0.1524)
				)
				(justify mirror)
			)
		)
		(property "Device Type" "R402H16"
			(at -0.064008 -5.517896 270)
			(unlocked yes)
			(layer "B.Fab")
			(hide yes)
			(effects
				(font
					(size 1.016 1.016)
					(thickness 0.1524)
				)
				(justify mirror)
			)
		)
		(duplicate_pad_numbers_are_jumpers no)
		(fp_rect
			(start 0.381 0.8382)
			(end -0.381 -0.8382)
			(stroke
				(width 0)
				(type default)
			)
			(fill no)
			(layer "B.CrtYd")
		)
		(fp_rect
			(start 0.381 0.8382)
			(end -0.381 -0.8382)
			(stroke
				(width 0)
				(type default)
			)
			(fill no)
			(layer "B.Fab")
		)
		(pad "1" smd custom
			(at 0 -0.4318 90)
			(size 0.127 0.127)
			(layers "B.Cu" "B.Mask" "B.Paste")
			(net "CLK_100M_CLKBUFF_NGFF_R_DN")
			(options
				(clearance outline)
				(anchor circle)
			)
			(primitives
				(gr_poly
					(pts
						(arc
							(start -0.2032 0.2794)
							(mid -0.239121 0.264521)
							(end -0.254 0.2286)
						)
						(arc
							(start -0.254 -0.2286)
							(mid -0.239121 -0.264521)
							(end -0.2032 -0.2794)
						)
						(arc
							(start 0.2032 -0.2794)
							(mid 0.239121 -0.264521)
							(end 0.254 -0.2286)
						)
						(arc
							(start 0.254 0.2286)
							(mid 0.239121 0.264521)
							(end 0.2032 0.2794)
						)
					)
					(width 0)
					(fill yes)
				)
			)
		)
		(pad "2" smd custom
			(at 0 0.4318 90)
			(size 0.127 0.127)
			(layers "B.Cu" "B.Mask" "B.Paste")
			(net "CLK_100M_CLKBUFF_NGFF_DN")
			(options
				(clearance outline)
				(anchor circle)
			)
			(primitives
				(gr_poly
					(pts
						(arc
							(start -0.2032 0.2794)
							(mid -0.239121 0.264521)
							(end -0.254 0.2286)
						)
						(arc
							(start -0.254 -0.2286)
							(mid -0.239121 -0.264521)
							(end -0.2032 -0.2794)
						)
						(arc
							(start 0.2032 -0.2794)
							(mid 0.239121 -0.264521)
							(end 0.254 -0.2286)
						)
						(arc
							(start 0.254 0.2286)
							(mid 0.239121 0.264521)
							(end 0.2032 0.2794)
						)
					)
					(width 0)
					(fill yes)
				)
			)
		)
	)
	(footprint ""
		(layer "B.Cu")
		(at 41.8846 -27.5336 180)
		(property "Reference" "R328"
			(at 0 0 0)
			(layer "B.SilkS")
			(hide yes)
			(effects
				(font
					(size 1.27 1.27)
				)
				(justify mirror)
			)
		)
		(property "Value" "33R2F-3-GP"
			(at -0.064008 -3.993896 180)
			(unlocked yes)
			(layer "B.Fab")
			(hide yes)
			(effects
				(font
					(size 1.016 1.016)
					(thickness 0.1524)
				)
				(justify mirror)
			)
		)
		(property "Device Type" "R402H16"
			(at -0.064008 -5.517896 180)
			(unlocked yes)
			(layer "B.Fab")
			(hide yes)
			(effects
				(font
					(size 1.016 1.016)
					(thickness 0.1524)
				)
				(justify mirror)
			)
		)
		(duplicate_pad_numbers_are_jumpers no)
		(fp_rect
			(start 0.381 0.8382)
			(end -0.381 -0.8382)
			(stroke
				(width 0)
				(type default)
			)
			(fill no)
			(layer "B.CrtYd")
		)
		(fp_rect
			(start 0.381 0.8382)
			(end -0.381 -0.8382)
			(stroke
				(width 0)
				(type default)
			)
			(fill no)
			(layer "B.Fab")
		)
		(pad "1" smd custom
			(at 0 -0.4318)
			(size 0.127 0.127)
			(layers "B.Cu" "B.Mask" "B.Paste")
			(net "CLK_100M_CLKBUFF_PCIE_R_DN")
			(options
				(clearance outline)
				(anchor circle)
			)
			(primitives
				(gr_poly
					(pts
						(arc
							(start -0.2032 0.2794)
							(mid -0.239121 0.264521)
							(end -0.254 0.2286)
						)
						(arc
							(start -0.254 -0.2286)
							(mid -0.239121 -0.264521)
							(end -0.2032 -0.2794)
						)
						(arc
							(start 0.2032 -0.2794)
							(mid 0.239121 -0.264521)
							(end 0.254 -0.2286)
						)
						(arc
							(start 0.254 0.2286)
							(mid 0.239121 0.264521)
							(end 0.2032 0.2794)
						)
					)
					(width 0)
					(fill yes)
				)
			)
		)
		(pad "2" smd custom
			(at 0 0.4318)
			(size 0.127 0.127)
			(layers "B.Cu" "B.Mask" "B.Paste")
			(net "CLK_100M_CLKBUFF_PCIE_DN")
			(options
				(clearance outline)
				(anchor circle)
			)
			(primitives
				(gr_poly
					(pts
						(arc
							(start -0.2032 0.2794)
							(mid -0.239121 0.264521)
							(end -0.254 0.2286)
						)
						(arc
							(start -0.254 -0.2286)
							(mid -0.239121 -0.264521)
							(end -0.2032 -0.2794)
						)
						(arc
							(start 0.2032 -0.2794)
							(mid 0.239121 -0.264521)
							(end 0.254 -0.2286)
						)
						(arc
							(start 0.254 0.2286)
							(mid 0.239121 0.264521)
							(end 0.2032 0.2794)
						)
					)
					(width 0)
					(fill yes)
				)
			)
		)
	)
	(footprint ""
		(layer "B.Cu")
		(at 99.06 -41.5544)
		(property "Reference" "C169"
			(at 0 0 0)
			(layer "B.SilkS")
			(hide yes)
			(effects
				(font
					(size 1.27 1.27)
				)
				(justify mirror)
			)
		)
		(property "Value" "SC1U10V2KX-1GP"
			(at -1.1811 -2.7051 0)
			(unlocked yes)
			(layer "B.Fab")
			(hide yes)
			(effects
				(font
					(size 1.016 1.016)
					(thickness 0.1524)
				)
				(justify mirror)
			)
		)
		(property "Device Type" "C402H22"
			(at -1.1811 -4.2291 0)
			(unlocked yes)
			(layer "B.Fab")
			(hide yes)
			(effects
				(font
					(size 1.016 1.016)
					(thickness 0.1524)
				)
				(justify mirror)
			)
		)
		(duplicate_pad_numbers_are_jumpers no)
		(fp_rect
			(start 0.381 0.7366)
			(end -0.381 -0.7366)
			(stroke
				(width 0)
				(type default)
			)
			(fill no)
			(layer "B.CrtYd")
		)
		(fp_rect
			(start 0.381 0.7366)
			(end -0.381 -0.7366)
			(stroke
				(width 0)
				(type default)
			)
			(fill no)
			(layer "B.Fab")
		)
		(pad "1" smd custom
			(at 0 -0.4572 180)
			(size 0.1143 0.1143)
			(layers "B.Cu" "B.Mask" "B.Paste")
			(net "PVNN")
			(options
				(clearance outline)
				(anchor circle)
			)
			(primitives
				(gr_poly
					(pts
						(arc
							(start -0.254 0.1778)
							(mid -0.239121 0.213721)
							(end -0.2032 0.2286)
						)
						(arc
							(start 0.2032 0.2286)
							(mid 0.239121 0.213721)
							(end 0.254 0.1778)
						)
						(arc
							(start 0.254 -0.1778)
							(mid 0.239121 -0.213721)
							(end 0.2032 -0.2286)
						)
						(arc
							(start -0.2032 -0.2286)
							(mid -0.239121 -0.213721)
							(end -0.254 -0.1778)
						)
					)
					(width 0)
					(fill yes)
				)
			)
		)
		(pad "2" smd custom
			(at 0 0.4572 180)
			(size 0.1143 0.1143)
			(layers "B.Cu" "B.Mask" "B.Paste")
			(net "GND")
			(options
				(clearance outline)
				(anchor circle)
			)
			(primitives
				(gr_poly
					(pts
						(arc
							(start -0.254 0.1778)
							(mid -0.239121 0.213721)
							(end -0.2032 0.2286)
						)
						(arc
							(start 0.2032 0.2286)
							(mid 0.239121 0.213721)
							(end 0.254 0.1778)
						)
						(arc
							(start 0.254 -0.1778)
							(mid 0.239121 -0.213721)
							(end 0.2032 -0.2286)
						)
						(arc
							(start -0.2032 -0.2286)
							(mid -0.239121 -0.213721)
							(end -0.254 -0.1778)
						)
					)
					(width 0)
					(fill yes)
				)
			)
		)
	)
	(footprint ""
		(layer "B.Cu")
		(at 18.5928 -60.6298 90)
		(property "Reference" "PR14"
			(at 0 0 90)
			(layer "B.SilkS")
			(hide yes)
			(effects
				(font
					(size 1.27 1.27)
				)
				(justify mirror)
			)
		)
		(property "Value" "1K5R2F-2-GP"
			(at -1.7907 -1.1176 90)
			(unlocked yes)
			(layer "B.Fab")
			(hide yes)
			(effects
				(font
					(size 1.016 1.016)
					(thickness 0.1524)
				)
				(justify mirror)
			)
		)
		(property "Device Type" "R402H16"
			(at -1.7907 -2.6416 90)
			(unlocked yes)
			(layer "B.Fab")
			(hide yes)
			(effects
				(font
					(size 1.016 1.016)
					(thickness 0.1524)
				)
				(justify mirror)
			)
		)
		(duplicate_pad_numbers_are_jumpers no)
		(fp_rect
			(start 0.381 0.8382)
			(end -0.381 -0.8382)
			(stroke
				(width 0)
				(type default)
			)
			(fill no)
			(layer "B.CrtYd")
		)
		(fp_rect
			(start 0.381 0.8382)
			(end -0.381 -0.8382)
			(stroke
				(width 0)
				(type default)
			)
			(fill no)
			(layer "B.Fab")
		)
		(pad "1" smd custom
			(at 0 -0.4318 270)
			(size 0.127 0.127)
			(layers "B.Cu" "B.Mask" "B.Paste")
			(net "VR_PVNN_COMP_RC")
			(options
				(clearance outline)
				(anchor circle)
			)
			(primitives
				(gr_poly
					(pts
						(arc
							(start -0.2032 0.2794)
							(mid -0.239121 0.264521)
							(end -0.254 0.2286)
						)
						(arc
							(start -0.254 -0.2286)
							(mid -0.239121 -0.264521)
							(end -0.2032 -0.2794)
						)
						(arc
							(start 0.2032 -0.2794)
							(mid 0.239121 -0.264521)
							(end 0.254 -0.2286)
						)
						(arc
							(start 0.254 0.2286)
							(mid 0.239121 0.264521)
							(end 0.2032 0.2794)
						)
					)
					(width 0)
					(fill yes)
				)
			)
		)
		(pad "2" smd custom
			(at 0 0.4318 270)
			(size 0.127 0.127)
			(layers "B.Cu" "B.Mask" "B.Paste")
			(net "VR_PVNN_FB")
			(options
				(clearance outline)
				(anchor circle)
			)
			(primitives
				(gr_poly
					(pts
						(arc
							(start -0.2032 0.2794)
							(mid -0.239121 0.264521)
							(end -0.254 0.2286)
						)
						(arc
							(start -0.254 -0.2286)
							(mid -0.239121 -0.264521)
							(end -0.2032 -0.2794)
						)
						(arc
							(start 0.2032 -0.2794)
							(mid 0.239121 -0.264521)
							(end 0.254 -0.2286)
						)
						(arc
							(start 0.254 0.2286)
							(mid 0.239121 0.264521)
							(end 0.2032 0.2794)
						)
					)
					(width 0)
					(fill yes)
				)
			)
		)
	)
)
